(kicad_pcb
	(version 20260206)
	(generator "pcbnew")
	(generator_version "10.0")
	(general
		(thickness 1.6)
		(legacy_teardrops no)
	)
	(paper "A4")
	(title_block
		(title "01162023_DA0F0TEBIF0_F0T_Expander_BD_F_brd_V02_OCP.brd")
		(comment 1 "Grand Teton / footprints 1522-1528 of 9728")
	)
	(layers
		(0 "F.Cu" signal "TOP")
		(4 "In1.Cu" signal "GND")
		(6 "In2.Cu" signal "VCC")
		(8 "In3.Cu" signal "VCC1")
		(10 "In4.Cu" signal "GND1")
		(12 "In5.Cu" signal "IN1")
		(14 "In6.Cu" signal "GND2")
		(16 "In7.Cu" signal "IN2")
		(18 "In8.Cu" signal "GND3")
		(20 "In9.Cu" signal "IN3")
		(22 "In10.Cu" signal "GND4")
		(24 "In11.Cu" signal "IN4")
		(26 "In12.Cu" signal "GND5")
		(28 "In13.Cu" signal "IN5")
		(30 "In14.Cu" signal "GND6")
		(32 "In15.Cu" signal "IN6")
		(34 "In16.Cu" signal "GND7")
		(2 "B.Cu" signal "BOTTOM")
		(9 "F.Adhes" user "F.Adhesive")
		(11 "B.Adhes" user "B.Adhesive")
		(13 "F.Paste" user "Package Geometry/Pastemask Top")
		(15 "B.Paste" user "Package Geometry/Pastemask Bottom")
		(5 "F.SilkS" user "Ref Des/Silkscreen Top")
		(7 "B.SilkS" user "Ref Des/Silkscreen Bottom")
		(1 "F.Mask" user "Board Geometry/Soldermask Top")
		(3 "B.Mask" user "Board Geometry/Soldermask Bottom")
		(17 "Dwgs.User" user "User.Drawings")
		(19 "Cmts.User" user "User.Comments")
		(21 "Eco1.User" user "User.Eco1")
		(23 "Eco2.User" user "User.Eco2")
		(25 "Edge.Cuts" user "Board Geometry/Outline")
		(27 "Margin" user)
		(31 "F.CrtYd" user "Package Geometry/Place Bound Top")
		(29 "B.CrtYd" user "Package Geometry/Place Bound Bottom")
		(35 "F.Fab" user "Ref Des/Assembly Top")
		(33 "B.Fab" user "Ref Des/Assembly Bottom")
	)
	(footprint ""
		(layer "F.Cu")
		(at 340.561422 -191.43345 180)
		(property "Reference" "R4241"
			(at 0 0 180)
			(layer "F.SilkS")
			(hide yes)
			(effects
				(font
					(size 1.27 1.27)
				)
			)
		)
		(property "Value" ""
			(at 0 0 180)
			(layer "F.Fab")
			(effects
				(font
					(size 1.27 1.27)
				)
			)
		)
		(duplicate_pad_numbers_are_jumpers no)
		(fp_line
			(start 0.7874 0.4064)
			(end -0.7874 0.4064)
			(stroke
				(width 0.1524)
				(type default)
			)
			(layer "F.SilkS")
		)
		(fp_line
			(start 0.7874 -0.4064)
			(end 0.7874 0.4064)
			(stroke
				(width 0.1524)
				(type default)
			)
			(layer "F.SilkS")
		)
		(fp_line
			(start -0.7874 0.4064)
			(end -0.7874 -0.4064)
			(stroke
				(width 0.1524)
				(type default)
			)
			(layer "F.SilkS")
		)
		(fp_line
			(start -0.7874 -0.4064)
			(end 0.7874 -0.4064)
			(stroke
				(width 0.1524)
				(type default)
			)
			(layer "F.SilkS")
		)
		(fp_line
			(start 0.67945 0.3048)
			(end 0.120396 0.3048)
			(stroke
				(width 0.1)
				(type default)
			)
			(layer "F.Fab")
		)
		(fp_line
			(start 0.67945 -0.3048)
			(end 0.67945 0.3048)
			(stroke
				(width 0.1)
				(type default)
			)
			(layer "F.Fab")
		)
		(fp_line
			(start 0.12065 -0.2794)
			(end 0.12065 -0.3048)
			(stroke
				(width 0.1)
				(type default)
			)
			(layer "F.Fab")
		)
		(fp_line
			(start 0.12065 -0.3048)
			(end 0.67945 -0.3048)
			(stroke
				(width 0.1)
				(type default)
			)
			(layer "F.Fab")
		)
		(fp_line
			(start 0.120396 0.3048)
			(end 0.120396 0.2794)
			(stroke
				(width 0.1)
				(type default)
			)
			(layer "F.Fab")
		)
		(fp_line
			(start 0.120396 0.2794)
			(end -0.12065 0.2794)
			(stroke
				(width 0.1)
				(type default)
			)
			(layer "F.Fab")
		)
		(fp_line
			(start -0.12065 0.3048)
			(end -0.67945 0.3048)
			(stroke
				(width 0.1)
				(type default)
			)
			(layer "F.Fab")
		)
		(fp_line
			(start -0.12065 0.2794)
			(end -0.12065 0.3048)
			(stroke
				(width 0.1)
				(type default)
			)
			(layer "F.Fab")
		)
		(fp_line
			(start -0.12065 -0.2794)
			(end 0.12065 -0.2794)
			(stroke
				(width 0.1)
				(type default)
			)
			(layer "F.Fab")
		)
		(fp_line
			(start -0.12065 -0.305054)
			(end -0.12065 -0.2794)
			(stroke
				(width 0.1)
				(type default)
			)
			(layer "F.Fab")
		)
		(fp_line
			(start -0.67945 0.3048)
			(end -0.67945 -0.305054)
			(stroke
				(width 0.1)
				(type default)
			)
			(layer "F.Fab")
		)
		(fp_line
			(start -0.67945 -0.305054)
			(end -0.12065 -0.305054)
			(stroke
				(width 0.1)
				(type default)
			)
			(layer "F.Fab")
		)
		(pad "1" smd circle
			(at -0.40005 0 180)
			(size 0 0)
			(layers "F.Cu" "F.Mask" "F.Paste")
			(net "P3V3_AUX")
		)
		(pad "2" smd circle
			(at 0.40005 0 180)
			(size 0 0)
			(layers "F.Cu" "F.Mask" "F.Paste")
			(net "PWRGD_DSW_PWROK")
		)
	)
	(footprint ""
		(layer "F.Cu")
		(at 124.149612 -157.812994)
		(property "Reference" "R945"
			(at 0 0 0)
			(layer "F.SilkS")
			(hide yes)
			(effects
				(font
					(size 1.27 1.27)
				)
			)
		)
		(property "Value" ""
			(at 0 0 0)
			(layer "F.Fab")
			(effects
				(font
					(size 1.27 1.27)
				)
			)
		)
		(duplicate_pad_numbers_are_jumpers no)
		(fp_line
			(start -0.7874 -0.4064)
			(end 0.7874 -0.4064)
			(stroke
				(width 0.1524)
				(type default)
			)
			(layer "F.SilkS")
		)
		(fp_line
			(start -0.7874 0.4064)
			(end -0.7874 -0.4064)
			(stroke
				(width 0.1524)
				(type default)
			)
			(layer "F.SilkS")
		)
		(fp_line
			(start 0.7874 -0.4064)
			(end 0.7874 0.4064)
			(stroke
				(width 0.1524)
				(type default)
			)
			(layer "F.SilkS")
		)
		(fp_line
			(start 0.7874 0.4064)
			(end -0.7874 0.4064)
			(stroke
				(width 0.1524)
				(type default)
			)
			(layer "F.SilkS")
		)
		(fp_line
			(start -0.67945 -0.305054)
			(end -0.12065 -0.305054)
			(stroke
				(width 0.1)
				(type default)
			)
			(layer "F.Fab")
		)
		(fp_line
			(start -0.67945 0.3048)
			(end -0.67945 -0.305054)
			(stroke
				(width 0.1)
				(type default)
			)
			(layer "F.Fab")
		)
		(fp_line
			(start -0.12065 -0.305054)
			(end -0.12065 -0.2794)
			(stroke
				(width 0.1)
				(type default)
			)
			(layer "F.Fab")
		)
		(fp_line
			(start -0.12065 -0.2794)
			(end 0.12065 -0.2794)
			(stroke
				(width 0.1)
				(type default)
			)
			(layer "F.Fab")
		)
		(fp_line
			(start -0.12065 0.2794)
			(end -0.12065 0.3048)
			(stroke
				(width 0.1)
				(type default)
			)
			(layer "F.Fab")
		)
		(fp_line
			(start -0.12065 0.3048)
			(end -0.67945 0.3048)
			(stroke
				(width 0.1)
				(type default)
			)
			(layer "F.Fab")
		)
		(fp_line
			(start 0.120396 0.2794)
			(end -0.12065 0.2794)
			(stroke
				(width 0.1)
				(type default)
			)
			(layer "F.Fab")
		)
		(fp_line
			(start 0.120396 0.3048)
			(end 0.120396 0.2794)
			(stroke
				(width 0.1)
				(type default)
			)
			(layer "F.Fab")
		)
		(fp_line
			(start 0.12065 -0.3048)
			(end 0.67945 -0.3048)
			(stroke
				(width 0.1)
				(type default)
			)
			(layer "F.Fab")
		)
		(fp_line
			(start 0.12065 -0.2794)
			(end 0.12065 -0.3048)
			(stroke
				(width 0.1)
				(type default)
			)
			(layer "F.Fab")
		)
		(fp_line
			(start 0.67945 -0.3048)
			(end 0.67945 0.3048)
			(stroke
				(width 0.1)
				(type default)
			)
			(layer "F.Fab")
		)
		(fp_line
			(start 0.67945 0.3048)
			(end 0.120396 0.3048)
			(stroke
				(width 0.1)
				(type default)
			)
			(layer "F.Fab")
		)
		(pad "1" smd circle
			(at -0.40005 0)
			(size 0 0)
			(layers "F.Cu" "F.Mask" "F.Paste")
			(net "P3V3_AUX")
		)
		(pad "2" smd circle
			(at 0.40005 0)
			(size 0 0)
			(layers "F.Cu" "F.Mask" "F.Paste")
			(net "PWRGD_P12V_NIC2_CO")
		)
	)
	(footprint ""
		(layer "F.Cu")
		(at 351.17024 -237.698534 90)
		(property "Reference" "R6834"
			(at 0 0 90)
			(layer "F.SilkS")
			(hide yes)
			(effects
				(font
					(size 1.27 1.27)
				)
			)
		)
		(property "Value" ""
			(at 0 0 90)
			(layer "F.Fab")
			(effects
				(font
					(size 1.27 1.27)
				)
			)
		)
		(duplicate_pad_numbers_are_jumpers no)
		(fp_line
			(start 0.7874 -0.4064)
			(end 0.7874 0.4064)
			(stroke
				(width 0.1524)
				(type default)
			)
			(layer "F.SilkS")
		)
		(fp_line
			(start -0.7874 -0.4064)
			(end 0.7874 -0.4064)
			(stroke
				(width 0.1524)
				(type default)
			)
			(layer "F.SilkS")
		)
		(fp_line
			(start 0.7874 0.4064)
			(end -0.7874 0.4064)
			(stroke
				(width 0.1524)
				(type default)
			)
			(layer "F.SilkS")
		)
		(fp_line
			(start -0.7874 0.4064)
			(end -0.7874 -0.4064)
			(stroke
				(width 0.1524)
				(type default)
			)
			(layer "F.SilkS")
		)
		(fp_line
			(start -0.12065 -0.305054)
			(end -0.12065 -0.2794)
			(stroke
				(width 0.1)
				(type default)
			)
			(layer "F.Fab")
		)
		(fp_line
			(start -0.67945 -0.305054)
			(end -0.12065 -0.305054)
			(stroke
				(width 0.1)
				(type default)
			)
			(layer "F.Fab")
		)
		(fp_line
			(start 0.67945 -0.3048)
			(end 0.67945 0.3048)
			(stroke
				(width 0.1)
				(type default)
			)
			(layer "F.Fab")
		)
		(fp_line
			(start 0.12065 -0.3048)
			(end 0.67945 -0.3048)
			(stroke
				(width 0.1)
				(type default)
			)
			(layer "F.Fab")
		)
		(fp_line
			(start 0.12065 -0.2794)
			(end 0.12065 -0.3048)
			(stroke
				(width 0.1)
				(type default)
			)
			(layer "F.Fab")
		)
		(fp_line
			(start -0.12065 -0.2794)
			(end 0.12065 -0.2794)
			(stroke
				(width 0.1)
				(type default)
			)
			(layer "F.Fab")
		)
		(fp_line
			(start 0.120396 0.2794)
			(end -0.12065 0.2794)
			(stroke
				(width 0.1)
				(type default)
			)
			(layer "F.Fab")
		)
		(fp_line
			(start -0.12065 0.2794)
			(end -0.12065 0.3048)
			(stroke
				(width 0.1)
				(type default)
			)
			(layer "F.Fab")
		)
		(fp_line
			(start 0.67945 0.3048)
			(end 0.120396 0.3048)
			(stroke
				(width 0.1)
				(type default)
			)
			(layer "F.Fab")
		)
		(fp_line
			(start 0.120396 0.3048)
			(end 0.120396 0.2794)
			(stroke
				(width 0.1)
				(type default)
			)
			(layer "F.Fab")
		)
		(fp_line
			(start -0.12065 0.3048)
			(end -0.67945 0.3048)
			(stroke
				(width 0.1)
				(type default)
			)
			(layer "F.Fab")
		)
		(fp_line
			(start -0.67945 0.3048)
			(end -0.67945 -0.305054)
			(stroke
				(width 0.1)
				(type default)
			)
			(layer "F.Fab")
		)
		(pad "1" smd circle
			(at -0.40005 0 90)
			(size 0 0)
			(layers "F.Cu" "F.Mask" "F.Paste")
			(net "SSD7_PWR_EN_R")
		)
		(pad "2" smd circle
			(at 0.40005 0 90)
			(size 0 0)
			(layers "F.Cu" "F.Mask" "F.Paste")
			(net "GND")
		)
	)
	(footprint ""
		(layer "F.Cu")
		(at 359.85831 -256.226564 180)
		(property "Reference" "PR134"
			(at 0 0 180)
			(layer "F.SilkS")
			(hide yes)
			(effects
				(font
					(size 1.27 1.27)
				)
			)
		)
		(property "Value" ""
			(at 0 0 180)
			(layer "F.Fab")
			(effects
				(font
					(size 1.27 1.27)
				)
			)
		)
		(duplicate_pad_numbers_are_jumpers no)
		(fp_line
			(start 0.7874 0.4064)
			(end -0.7874 0.4064)
			(stroke
				(width 0.1524)
				(type default)
			)
			(layer "F.SilkS")
		)
		(fp_line
			(start 0.7874 -0.4064)
			(end 0.7874 0.4064)
			(stroke
				(width 0.1524)
				(type default)
			)
			(layer "F.SilkS")
		)
		(fp_line
			(start -0.7874 0.4064)
			(end -0.7874 -0.4064)
			(stroke
				(width 0.1524)
				(type default)
			)
			(layer "F.SilkS")
		)
		(fp_line
			(start -0.7874 -0.4064)
			(end 0.7874 -0.4064)
			(stroke
				(width 0.1524)
				(type default)
			)
			(layer "F.SilkS")
		)
		(fp_line
			(start 0.67945 0.3048)
			(end 0.120396 0.3048)
			(stroke
				(width 0.1)
				(type default)
			)
			(layer "F.Fab")
		)
		(fp_line
			(start 0.67945 -0.3048)
			(end 0.67945 0.3048)
			(stroke
				(width 0.1)
				(type default)
			)
			(layer "F.Fab")
		)
		(fp_line
			(start 0.12065 -0.2794)
			(end 0.12065 -0.3048)
			(stroke
				(width 0.1)
				(type default)
			)
			(layer "F.Fab")
		)
		(fp_line
			(start 0.12065 -0.3048)
			(end 0.67945 -0.3048)
			(stroke
				(width 0.1)
				(type default)
			)
			(layer "F.Fab")
		)
		(fp_line
			(start 0.120396 0.3048)
			(end 0.120396 0.2794)
			(stroke
				(width 0.1)
				(type default)
			)
			(layer "F.Fab")
		)
		(fp_line
			(start 0.120396 0.2794)
			(end -0.12065 0.2794)
			(stroke
				(width 0.1)
				(type default)
			)
			(layer "F.Fab")
		)
		(fp_line
			(start -0.12065 0.3048)
			(end -0.67945 0.3048)
			(stroke
				(width 0.1)
				(type default)
			)
			(layer "F.Fab")
		)
		(fp_line
			(start -0.12065 0.2794)
			(end -0.12065 0.3048)
			(stroke
				(width 0.1)
				(type default)
			)
			(layer "F.Fab")
		)
		(fp_line
			(start -0.12065 -0.2794)
			(end 0.12065 -0.2794)
			(stroke
				(width 0.1)
				(type default)
			)
			(layer "F.Fab")
		)
		(fp_line
			(start -0.12065 -0.305054)
			(end -0.12065 -0.2794)
			(stroke
				(width 0.1)
				(type default)
			)
			(layer "F.Fab")
		)
		(fp_line
			(start -0.67945 0.3048)
			(end -0.67945 -0.305054)
			(stroke
				(width 0.1)
				(type default)
			)
			(layer "F.Fab")
		)
		(fp_line
			(start -0.67945 -0.305054)
			(end -0.12065 -0.305054)
			(stroke
				(width 0.1)
				(type default)
			)
			(layer "F.Fab")
		)
		(pad "1" smd circle
			(at -0.40005 0 180)
			(size 0 0)
			(layers "F.Cu" "F.Mask" "F.Paste")
			(net "P3V3_AUX")
		)
		(pad "2" smd circle
			(at 0.40005 0 180)
			(size 0 0)
			(layers "F.Cu" "F.Mask" "F.Paste")
			(net "P0V8_PEX2_VRHOT_R")
		)
	)
	(footprint ""
		(layer "F.Cu")
		(at 384.938524 -131.323334)
		(property "Reference" "C673"
			(at 0 0 0)
			(layer "F.SilkS")
			(hide yes)
			(effects
				(font
					(size 1.27 1.27)
				)
			)
		)
		(property "Value" ""
			(at 0 0 0)
			(layer "F.Fab")
			(effects
				(font
					(size 1.27 1.27)
				)
			)
		)
		(duplicate_pad_numbers_are_jumpers no)
		(fp_line
			(start -0.299974 -0.150114)
			(end 0.299974 -0.150114)
			(stroke
				(width 0.1)
				(type default)
			)
			(layer "F.Fab")
		)
		(fp_line
			(start -0.299974 0.150114)
			(end -0.299974 -0.150114)
			(stroke
				(width 0.1)
				(type default)
			)
			(layer "F.Fab")
		)
		(fp_line
			(start 0.299974 -0.150114)
			(end 0.299974 0.150114)
			(stroke
				(width 0.1)
				(type default)
			)
			(layer "F.Fab")
		)
		(fp_line
			(start 0.299974 0.150114)
			(end -0.299974 0.150114)
			(stroke
				(width 0.1)
				(type default)
			)
			(layer "F.Fab")
		)
		(pad "1" smd rect
			(at -0.2667 0)
			(size 0.3048 0.381)
			(layers "F.Cu" "F.Mask" "F.Paste")
			(net "P5E_PEX3_STN1_TX_DN<28>")
		)
		(pad "2" smd rect
			(at 0.2667 0)
			(size 0.3048 0.381)
			(layers "F.Cu" "F.Mask" "F.Paste")
			(net "P5E_PEX3_STN1_TX_C_DN<28>")
		)
	)
	(footprint ""
		(layer "F.Cu")
		(at 258.46786 -55.083456)
		(property "Reference" "PC408"
			(at 0 0 0)
			(layer "F.SilkS")
			(hide yes)
			(effects
				(font
					(size 1.27 1.27)
				)
			)
		)
		(property "Value" ""
			(at 0 0 0)
			(layer "F.Fab")
			(effects
				(font
					(size 1.27 1.27)
				)
			)
		)
		(duplicate_pad_numbers_are_jumpers no)
		(fp_line
			(start -0.7874 -0.4064)
			(end 0.7874 -0.4064)
			(stroke
				(width 0.1524)
				(type default)
			)
			(layer "F.SilkS")
		)
		(fp_line
			(start -0.7874 0.4064)
			(end -0.7874 -0.4064)
			(stroke
				(width 0.1524)
				(type default)
			)
			(layer "F.SilkS")
		)
		(fp_line
			(start 0.7874 -0.4064)
			(end 0.7874 0.4064)
			(stroke
				(width 0.1524)
				(type default)
			)
			(layer "F.SilkS")
		)
		(fp_line
			(start 0.7874 0.4064)
			(end -0.7874 0.4064)
			(stroke
				(width 0.1524)
				(type default)
			)
			(layer "F.SilkS")
		)
		(fp_line
			(start -0.67945 -0.305054)
			(end -0.12065 -0.305054)
			(stroke
				(width 0.1)
				(type default)
			)
			(layer "F.Fab")
		)
		(fp_line
			(start -0.67945 0.3048)
			(end -0.67945 -0.305054)
			(stroke
				(width 0.1)
				(type default)
			)
			(layer "F.Fab")
		)
		(fp_line
			(start -0.12065 -0.305054)
			(end -0.12065 -0.2794)
			(stroke
				(width 0.1)
				(type default)
			)
			(layer "F.Fab")
		)
		(fp_line
			(start -0.12065 -0.2794)
			(end 0.12065 -0.2794)
			(stroke
				(width 0.1)
				(type default)
			)
			(layer "F.Fab")
		)
		(fp_line
			(start -0.12065 0.2794)
			(end -0.12065 0.3048)
			(stroke
				(width 0.1)
				(type default)
			)
			(layer "F.Fab")
		)
		(fp_line
			(start -0.12065 0.3048)
			(end -0.67945 0.3048)
			(stroke
				(width 0.1)
				(type default)
			)
			(layer "F.Fab")
		)
		(fp_line
			(start 0.120396 0.2794)
			(end -0.12065 0.2794)
			(stroke
				(width 0.1)
				(type default)
			)
			(layer "F.Fab")
		)
		(fp_line
			(start 0.120396 0.3048)
			(end 0.120396 0.2794)
			(stroke
				(width 0.1)
				(type default)
			)
			(layer "F.Fab")
		)
		(fp_line
			(start 0.12065 -0.3048)
			(end 0.67945 -0.3048)
			(stroke
				(width 0.1)
				(type default)
			)
			(layer "F.Fab")
		)
		(fp_line
			(start 0.12065 -0.2794)
			(end 0.12065 -0.3048)
			(stroke
				(width 0.1)
				(type default)
			)
			(layer "F.Fab")
		)
		(fp_line
			(start 0.67945 -0.3048)
			(end 0.67945 0.3048)
			(stroke
				(width 0.1)
				(type default)
			)
			(layer "F.Fab")
		)
		(fp_line
			(start 0.67945 0.3048)
			(end 0.120396 0.3048)
			(stroke
				(width 0.1)
				(type default)
			)
			(layer "F.Fab")
		)
		(pad "1" smd circle
			(at -0.40005 0)
			(size 0 0)
			(layers "F.Cu" "F.Mask" "F.Paste")
			(net "P5V_AUX")
		)
		(pad "2" smd circle
			(at 0.40005 0)
			(size 0 0)
			(layers "F.Cu" "F.Mask" "F.Paste")
			(net "GND")
		)
	)
	(footprint ""
		(layer "F.Cu")
		(at 413.867854 -223.863662)
		(property "Reference" "J68"
			(at -7.126986 0.264668 0)
			(unlocked yes)
			(layer "F.SilkS")
			(effects
				(font
					(size 0.7874 0.5842)
					(thickness 0.1524)
				)
				(justify left)
			)
		)
		(property "Value" ""
			(at 0 0 0)
			(layer "F.Fab")
			(effects
				(font
					(size 1.27 1.27)
				)
			)
		)
		(duplicate_pad_numbers_are_jumpers no)
		(fp_line
			(start -1.27 -3.81)
			(end 1.27 -3.81)
			(stroke
				(width 0.1524)
				(type default)
			)
			(layer "F.SilkS")
		)
		(fp_line
			(start -1.27 -0.7747)
			(end -1.27 -3.81)
			(stroke
				(width 0.1524)
				(type default)
			)
			(layer "F.SilkS")
		)
		(fp_line
			(start -1.27 3.81)
			(end -1.27 0.7747)
			(stroke
				(width 0.1524)
				(type default)
			)
			(layer "F.SilkS")
		)
		(fp_line
			(start 1.27 -3.81)
			(end 1.27 -3.3147)
			(stroke
				(width 0.1524)
				(type default)
			)
			(layer "F.SilkS")
		)
		(fp_line
			(start 1.27 -1.7653)
			(end 1.27 1.7653)
			(stroke
				(width 0.1524)
				(type default)
			)
			(layer "F.SilkS")
		)
		(fp_line
			(start 1.27 3.3147)
			(end 1.27 3.81)
			(stroke
				(width 0.1524)
				(type default)
			)
			(layer "F.SilkS")
		)
		(fp_line
			(start 1.27 3.81)
			(end -1.27 3.81)
			(stroke
				(width 0.1524)
				(type default)
			)
			(layer "F.SilkS")
		)
		(fp_poly
			(pts
				(xy 4.3942 -3.048) (xy 4.3942 -2.032) (xy 3.3782 -2.54)
			)
			(stroke
				(width 0)
				(type default)
			)
			(fill yes)
			(layer "F.SilkS")
		)
		(fp_line
			(start -1.27 -3.81)
			(end -1.27 3.81)
			(stroke
				(width 0.1)
				(type default)
			)
			(layer "F.Fab")
		)
		(fp_line
			(start -1.27 3.81)
			(end 1.27 3.81)
			(stroke
				(width 0.1)
				(type default)
			)
			(layer "F.Fab")
		)
		(fp_line
			(start 1.27 -3.81)
			(end -1.27 -3.81)
			(stroke
				(width 0.1)
				(type default)
			)
			(layer "F.Fab")
		)
		(fp_line
			(start 1.27 3.81)
			(end 1.27 -3.81)
			(stroke
				(width 0.1)
				(type default)
			)
			(layer "F.Fab")
		)
		(fp_poly
			(pts
				(xy 4.3942 -3.048) (xy 4.3942 -2.032) (xy 3.3782 -2.54)
			)
			(stroke
				(width 0)
				(type default)
			)
			(fill yes)
			(layer "F.Fab")
		)
		(fp_text user "3"
			(at 3.921252 2.54 90)
			(unlocked yes)
			(layer "F.SilkS")
			(effects
				(font
					(size 0.7874 0.5842)
					(thickness 0.1524)
				)
			)
		)
		(fp_text user "3"
			(at 3.921252 2.54 90)
			(unlocked yes)
			(layer "F.Fab")
			(effects
				(font
					(size 0.7874 0.5842)
					(thickness 0.1524)
				)
			)
		)
		(pad "1" smd rect
			(at 1.459992 -2.54 90)
			(size 1.27 3.429)
			(layers "F.Cu" "F.Mask" "F.Paste")
			(net "GND")
		)
		(pad "2" smd rect
			(at -1.459992 0 90)
			(size 1.27 3.429)
			(layers "F.Cu" "F.Mask" "F.Paste")
			(net "UART_PEX0_SDB_BUF_R1_TX")
		)
		(pad "3" smd rect
			(at 1.459992 2.54 90)
			(size 1.27 3.429)
			(layers "F.Cu" "F.Mask" "F.Paste")
			(net "UART_PEX0_SDB_R1_RX")
		)
	)
)
